G04 ================== begin FILE IDENTIFICATION RECORD ==================*
G04 Layout Name:  17301-sa.brd*
G04 Film Name:    DP_REF_L1*
G04 File Format:  Gerber RS274X*
G04 File Origin:  Cadence Allegro 16.6-2015-S079*
G04 Origin Date:  Thu Jun 22 17:50:07 2017*
G04 *
G04 Layer:  BOARD GEOMETRY/PANEL_OUTLINE*
G04 Layer:  BOARD GEOMETRY/DP_REF_L1_TBL*
G04 Layer:  BOARD GEOMETRY/DP_REF_L1_TOP*
G04 *
G04 Offset:    (0.00 0.00)*
G04 Mirror:    No*
G04 Mode:      Positive*
G04 Rotation:  0*
G04 FullContactRelief:  No*
G04 UndefLineWidth:     6.00*
G04 ================== end FILE IDENTIFICATION RECORD ====================*
%FSLAX35Y35*MOIN*%
%IR0*IPPOS*OFA0.00000B0.00000*MIA0B0*SFA1.00000B1.00000*%
%ADD10C,.02*%
%ADD11C,.006*%
%ADD12C,.0084*%
G75*
%LPD*%
G75*
G54D10*
G01X615261Y627846D02*
X1350261D01*
G01X615261Y697146D02*
Y627846D01*
G01Y662496D02*
X1350261D01*
G01X615261Y697146D02*
X1350261D01*
G01X790261D02*
Y627846D01*
G01X1035261Y697146D02*
Y627846D01*
G01X1140261Y697146D02*
Y627846D01*
G01X1350261Y697146D02*
Y627846D01*
G54D11*
G01X-19340Y-32800D02*
Y-50300D01*
G01X-24362Y-32800D02*
X-14318D01*
G01X-5552Y-50300D02*
Y-32800D01*
G01Y-41258D02*
X-4460Y-39800D01*
X-3368Y-38925D01*
X-1622Y-38634D01*
X-312Y-38925D01*
X1217Y-40092D01*
X1872Y-41842D01*
Y-50300D01*
G01X15660Y-38634D02*
Y-50300D01*
G01Y-33967D02*
X15223Y-33675D01*
Y-33092D01*
X15660Y-32800D01*
X16097Y-33092D01*
Y-33675D01*
X15660Y-33967D01*
G01X29885Y-48259D02*
X30977Y-49425D01*
X32505Y-50300D01*
X33815D01*
X35125Y-49717D01*
X35998Y-48842D01*
X36435Y-47676D01*
X36217Y-45925D01*
X35343Y-45050D01*
X31413Y-43300D01*
X30540Y-41258D01*
X30977Y-39800D01*
X31850Y-38925D01*
X33160Y-38634D01*
X34470Y-38925D01*
X35780Y-39800D01*
G01X65103Y-54675D02*
X66632Y-55842D01*
X68378Y-56133D01*
X69906Y-55842D01*
X71217Y-54384D01*
X72090Y-52342D01*
Y-38634D01*
G01Y-40967D02*
X71217Y-39800D01*
X69906Y-38925D01*
X68378Y-38634D01*
X66632Y-39217D01*
X65540Y-40383D01*
X64666Y-42425D01*
X64230Y-44467D01*
X64448Y-46217D01*
X65322Y-48259D01*
X66632Y-49717D01*
X68378Y-50300D01*
X69688Y-50008D01*
X71217Y-48842D01*
X72090Y-47676D01*
G01X82385Y-42425D02*
X89372D01*
X88717Y-40383D01*
X87625Y-39217D01*
X86097Y-38634D01*
X84568Y-38925D01*
X83258Y-39800D01*
X82385Y-41842D01*
X81948Y-43592D01*
Y-45342D01*
X82385Y-47092D01*
X83477Y-48842D01*
X84787Y-50008D01*
X86315Y-50300D01*
X87843Y-49717D01*
X89372Y-47967D01*
G01X100103Y-50300D02*
Y-38634D01*
G01Y-40967D02*
X101195Y-39800D01*
X102287Y-38925D01*
X103815Y-38634D01*
X104906Y-38925D01*
X106217Y-39800D01*
G01X116730Y-50300D02*
Y-32800D01*
G01Y-41550D02*
X117822Y-39800D01*
X119132Y-38925D01*
X120442Y-38634D01*
X122406Y-39217D01*
X123717Y-40383D01*
X124590Y-42425D01*
Y-44758D01*
X124153Y-47092D01*
X123280Y-48842D01*
X121752Y-50008D01*
X120442Y-50300D01*
X119132Y-50008D01*
X117822Y-49134D01*
X116730Y-47676D01*
G01X134885Y-42425D02*
X141872D01*
X141217Y-40383D01*
X140125Y-39217D01*
X138597Y-38634D01*
X137068Y-38925D01*
X135758Y-39800D01*
X134885Y-41842D01*
X134448Y-43592D01*
Y-45342D01*
X134885Y-47092D01*
X135977Y-48842D01*
X137287Y-50008D01*
X138815Y-50300D01*
X140343Y-49717D01*
X141872Y-47967D01*
G01X152603Y-50300D02*
Y-38634D01*
G01Y-40967D02*
X153695Y-39800D01*
X154787Y-38925D01*
X156315Y-38634D01*
X157406Y-38925D01*
X158717Y-39800D01*
G01X190660Y-38634D02*
Y-50300D01*
G01Y-33967D02*
X190223Y-33675D01*
Y-33092D01*
X190660Y-32800D01*
X191097Y-33092D01*
Y-33675D01*
X190660Y-33967D01*
G01X204885Y-48259D02*
X205977Y-49425D01*
X207505Y-50300D01*
X208815D01*
X210125Y-49717D01*
X210998Y-48842D01*
X211435Y-47676D01*
X211217Y-45925D01*
X210343Y-45050D01*
X206413Y-43300D01*
X205540Y-41258D01*
X205977Y-39800D01*
X206850Y-38925D01*
X208160Y-38634D01*
X209470Y-38925D01*
X210780Y-39800D01*
G01X239666Y-54675D02*
X241195Y-55842D01*
X242505Y-56133D01*
X244252Y-55550D01*
X245562Y-54092D01*
X246217Y-51466D01*
Y-38634D01*
G01Y-33967D02*
X245780Y-33675D01*
Y-33092D01*
X246217Y-32800D01*
X246653Y-33092D01*
Y-33675D01*
X246217Y-33967D01*
G01X256948Y-38634D02*
Y-46800D01*
X257822Y-48842D01*
X259132Y-50008D01*
X260660Y-50300D01*
X262188Y-50008D01*
X263498Y-48842D01*
X264372Y-46800D01*
G01Y-50300D02*
Y-38634D01*
G01X274885Y-48259D02*
X275977Y-49425D01*
X277505Y-50300D01*
X278815D01*
X280125Y-49717D01*
X280998Y-48842D01*
X281435Y-47676D01*
X281217Y-45925D01*
X280343Y-45050D01*
X276413Y-43300D01*
X275540Y-41258D01*
X275977Y-39800D01*
X276850Y-38925D01*
X278160Y-38634D01*
X279470Y-38925D01*
X280780Y-39800D01*
G01X295660Y-32800D02*
Y-50300D01*
G01X292603Y-38634D02*
X298717D01*
G01X329350Y-50300D02*
Y-35425D01*
X329787Y-33967D01*
X330660Y-33092D01*
X331970Y-32800D01*
X333280Y-33383D01*
X333935Y-34842D01*
G01X331315Y-39800D02*
X326948D01*
G01X348160Y-50300D02*
X346850Y-50008D01*
X345540Y-48842D01*
X344666Y-46800D01*
X344230Y-44467D01*
X344666Y-42133D01*
X345540Y-40092D01*
X346850Y-38925D01*
X348160Y-38634D01*
X349470Y-38925D01*
X350780Y-40092D01*
X351653Y-42133D01*
X351872Y-44467D01*
X351653Y-46800D01*
X350780Y-48842D01*
X349470Y-50008D01*
X348160Y-50300D01*
G01X362603D02*
Y-38634D01*
G01Y-40967D02*
X363695Y-39800D01*
X364787Y-38925D01*
X366315Y-38634D01*
X367406Y-38925D01*
X368717Y-39800D01*
G01X396075Y-55550D02*
X397385Y-56133D01*
X399132Y-55550D01*
X400223Y-54384D01*
X401097Y-52925D01*
X402406Y-48259D01*
X405245Y-38634D01*
G01X398258D02*
X402406Y-48259D01*
G01X418160Y-50300D02*
X416850Y-50008D01*
X415540Y-48842D01*
X414666Y-46800D01*
X414230Y-44467D01*
X414666Y-42133D01*
X415540Y-40092D01*
X416850Y-38925D01*
X418160Y-38634D01*
X419470Y-38925D01*
X420780Y-40092D01*
X421653Y-42133D01*
X421872Y-44467D01*
X421653Y-46800D01*
X420780Y-48842D01*
X419470Y-50008D01*
X418160Y-50300D01*
G01X431948Y-38634D02*
Y-46800D01*
X432822Y-48842D01*
X434132Y-50008D01*
X435660Y-50300D01*
X437188Y-50008D01*
X438498Y-48842D01*
X439372Y-46800D01*
G01Y-50300D02*
Y-38634D01*
G01X450103Y-50300D02*
Y-38634D01*
G01Y-40967D02*
X451195Y-39800D01*
X452287Y-38925D01*
X453815Y-38634D01*
X454906Y-38925D01*
X456217Y-39800D01*
G01X485103Y-50300D02*
Y-38634D01*
G01Y-40967D02*
X486195Y-39800D01*
X487287Y-38925D01*
X488815Y-38634D01*
X489906Y-38925D01*
X491217Y-39800D01*
G01X502385Y-42425D02*
X509372D01*
X508717Y-40383D01*
X507625Y-39217D01*
X506097Y-38634D01*
X504568Y-38925D01*
X503258Y-39800D01*
X502385Y-41842D01*
X501948Y-43592D01*
Y-45342D01*
X502385Y-47092D01*
X503477Y-48842D01*
X504787Y-50008D01*
X506315Y-50300D01*
X507843Y-49717D01*
X509372Y-47967D01*
G01X521850Y-50300D02*
Y-35425D01*
X522287Y-33967D01*
X523160Y-33092D01*
X524470Y-32800D01*
X525780Y-33383D01*
X526435Y-34842D01*
G01X523815Y-39800D02*
X519448D01*
G01X537385Y-42425D02*
X544372D01*
X543717Y-40383D01*
X542625Y-39217D01*
X541097Y-38634D01*
X539568Y-38925D01*
X538258Y-39800D01*
X537385Y-41842D01*
X536948Y-43592D01*
Y-45342D01*
X537385Y-47092D01*
X538477Y-48842D01*
X539787Y-50008D01*
X541315Y-50300D01*
X542843Y-49717D01*
X544372Y-47967D01*
G01X555103Y-50300D02*
Y-38634D01*
G01Y-40967D02*
X556195Y-39800D01*
X557287Y-38925D01*
X558815Y-38634D01*
X559906Y-38925D01*
X561217Y-39800D01*
G01X572385Y-42425D02*
X579372D01*
X578717Y-40383D01*
X577625Y-39217D01*
X576097Y-38634D01*
X574568Y-38925D01*
X573258Y-39800D01*
X572385Y-41842D01*
X571948Y-43592D01*
Y-45342D01*
X572385Y-47092D01*
X573477Y-48842D01*
X574787Y-50008D01*
X576315Y-50300D01*
X577843Y-49717D01*
X579372Y-47967D01*
G01X589448Y-50300D02*
Y-38634D01*
G01Y-41550D02*
X590322Y-40092D01*
X591632Y-38925D01*
X593378Y-38634D01*
X594906Y-38925D01*
X596217Y-40092D01*
X596872Y-42133D01*
Y-50300D01*
G01X614153Y-40092D02*
X612625Y-38925D01*
X611315Y-38634D01*
X609568Y-39217D01*
X608258Y-40383D01*
X607385Y-42425D01*
X607166Y-44467D01*
X607385Y-46509D01*
X608258Y-48259D01*
X609568Y-49717D01*
X611315Y-50300D01*
X612843Y-49717D01*
X614153Y-48550D01*
G01X624885Y-42425D02*
X631872D01*
X631217Y-40383D01*
X630125Y-39217D01*
X628597Y-38634D01*
X627068Y-38925D01*
X625758Y-39800D01*
X624885Y-41842D01*
X624448Y-43592D01*
Y-45342D01*
X624885Y-47092D01*
X625977Y-48842D01*
X627287Y-50008D01*
X628815Y-50300D01*
X630343Y-49717D01*
X631872Y-47967D01*
G01X663160Y-32800D02*
Y-50300D01*
G01X660103Y-38634D02*
X666217D01*
G01X680660Y-50300D02*
X679350Y-50008D01*
X678040Y-48842D01*
X677166Y-46800D01*
X676730Y-44467D01*
X677166Y-42133D01*
X678040Y-40092D01*
X679350Y-38925D01*
X680660Y-38634D01*
X681970Y-38925D01*
X683280Y-40092D01*
X684153Y-42133D01*
X684372Y-44467D01*
X684153Y-46800D01*
X683280Y-48842D01*
X681970Y-50008D01*
X680660Y-50300D01*
G01X714350D02*
Y-35425D01*
X714787Y-33967D01*
X715660Y-33092D01*
X716970Y-32800D01*
X718280Y-33383D01*
X718935Y-34842D01*
G01X716315Y-39800D02*
X711948D01*
G01X733160Y-38634D02*
Y-50300D01*
G01Y-33967D02*
X732723Y-33675D01*
Y-33092D01*
X733160Y-32800D01*
X733597Y-33092D01*
Y-33675D01*
X733160Y-33967D01*
G01X746948Y-50300D02*
Y-38634D01*
G01Y-41550D02*
X747822Y-40092D01*
X749132Y-38925D01*
X750878Y-38634D01*
X752406Y-38925D01*
X753717Y-40092D01*
X754372Y-42133D01*
Y-50300D01*
G01X772090Y-32800D02*
Y-50300D01*
G01Y-47676D02*
X771217Y-49134D01*
X769906Y-50008D01*
X768378Y-50300D01*
X766632Y-49717D01*
X765322Y-48259D01*
X764448Y-46509D01*
X764230Y-44467D01*
X764448Y-42425D01*
X765322Y-40675D01*
X766632Y-39217D01*
X768378Y-38634D01*
X769906Y-38925D01*
X770998Y-39509D01*
X772090Y-40675D01*
G01X803160Y-32800D02*
Y-50300D01*
G01X800103Y-38634D02*
X806217D01*
G01X816948Y-50300D02*
Y-32800D01*
G01Y-41258D02*
X818040Y-39800D01*
X819132Y-38925D01*
X820878Y-38634D01*
X822188Y-38925D01*
X823717Y-40092D01*
X824372Y-41842D01*
Y-50300D01*
G01X834885Y-42425D02*
X841872D01*
X841217Y-40383D01*
X840125Y-39217D01*
X838597Y-38634D01*
X837068Y-38925D01*
X835758Y-39800D01*
X834885Y-41842D01*
X834448Y-43592D01*
Y-45342D01*
X834885Y-47092D01*
X835977Y-48842D01*
X837287Y-50008D01*
X838815Y-50300D01*
X840343Y-49717D01*
X841872Y-47967D01*
G01X868357Y-50300D02*
Y-32800D01*
X872723D01*
X874470Y-33675D01*
X875780Y-34842D01*
X876872Y-36591D01*
X877745Y-38634D01*
X877963Y-41550D01*
X877745Y-44467D01*
X876872Y-46509D01*
X875780Y-48259D01*
X874470Y-49425D01*
X872723Y-50300D01*
X868357D01*
G01X886293D02*
Y-32800D01*
X891533D01*
X893280Y-33675D01*
X894590Y-35717D01*
X895027Y-38050D01*
X894590Y-40383D01*
X893498Y-42133D01*
X891533Y-43009D01*
X886293D01*
G01X925660Y-38634D02*
Y-50300D01*
G01Y-33967D02*
X925223Y-33675D01*
Y-33092D01*
X925660Y-32800D01*
X926097Y-33092D01*
Y-33675D01*
X925660Y-33967D01*
G01X936610Y-50300D02*
Y-38634D01*
G01Y-41842D02*
X937265Y-40383D01*
X938357Y-39217D01*
X939885Y-38634D01*
X941413Y-39217D01*
X942505Y-40383D01*
X943160Y-41842D01*
Y-50300D01*
G01Y-41842D02*
X943815Y-40383D01*
X944906Y-39217D01*
X946435Y-38634D01*
X947963Y-39217D01*
X949055Y-40383D01*
X949710Y-42133D01*
Y-50300D01*
G01X956730Y-56133D02*
Y-38634D01*
G01Y-41258D02*
X957822Y-39800D01*
X958913Y-38925D01*
X960660Y-38634D01*
X962188Y-38925D01*
X963717Y-40383D01*
X964372Y-42425D01*
X964590Y-44467D01*
X964372Y-46509D01*
X963717Y-48550D01*
X962406Y-49717D01*
X960660Y-50300D01*
X959132Y-50008D01*
X957603Y-49134D01*
X956730Y-47967D01*
G01X974885Y-42425D02*
X981872D01*
X981217Y-40383D01*
X980125Y-39217D01*
X978597Y-38634D01*
X977068Y-38925D01*
X975758Y-39800D01*
X974885Y-41842D01*
X974448Y-43592D01*
Y-45342D01*
X974885Y-47092D01*
X975977Y-48842D01*
X977287Y-50008D01*
X978815Y-50300D01*
X980343Y-49717D01*
X981872Y-47967D01*
G01X999590Y-32800D02*
Y-50300D01*
G01Y-47676D02*
X998717Y-49134D01*
X997406Y-50008D01*
X995878Y-50300D01*
X994132Y-49717D01*
X992822Y-48259D01*
X991948Y-46509D01*
X991730Y-44467D01*
X991948Y-42425D01*
X992822Y-40675D01*
X994132Y-39217D01*
X995878Y-38634D01*
X997406Y-38925D01*
X998498Y-39509D01*
X999590Y-40675D01*
G01X1017090Y-50300D02*
Y-38634D01*
G01Y-40675D02*
X1016217Y-39509D01*
X1014906Y-38925D01*
X1013378Y-38634D01*
X1011850Y-39217D01*
X1010540Y-40383D01*
X1009666Y-42133D01*
X1009230Y-44467D01*
X1009666Y-46800D01*
X1010540Y-48550D01*
X1011850Y-49717D01*
X1013378Y-50300D01*
X1014906Y-50008D01*
X1016217Y-49134D01*
X1017090Y-47967D01*
G01X1026948Y-50300D02*
Y-38634D01*
G01Y-41550D02*
X1027822Y-40092D01*
X1029132Y-38925D01*
X1030878Y-38634D01*
X1032406Y-38925D01*
X1033717Y-40092D01*
X1034372Y-42133D01*
Y-50300D01*
G01X1051653Y-40092D02*
X1050125Y-38925D01*
X1048815Y-38634D01*
X1047068Y-39217D01*
X1045758Y-40383D01*
X1044885Y-42425D01*
X1044666Y-44467D01*
X1044885Y-46509D01*
X1045758Y-48259D01*
X1047068Y-49717D01*
X1048815Y-50300D01*
X1050343Y-49717D01*
X1051653Y-48550D01*
G01X1062385Y-42425D02*
X1069372D01*
X1068717Y-40383D01*
X1067625Y-39217D01*
X1066097Y-38634D01*
X1064568Y-38925D01*
X1063258Y-39800D01*
X1062385Y-41842D01*
X1061948Y-43592D01*
Y-45342D01*
X1062385Y-47092D01*
X1063477Y-48842D01*
X1064787Y-50008D01*
X1066315Y-50300D01*
X1067843Y-49717D01*
X1069372Y-47967D01*
G01X1100660Y-32800D02*
Y-50300D01*
G01X1097603Y-38634D02*
X1103717D01*
G01X1115103Y-50300D02*
Y-38634D01*
G01Y-40967D02*
X1116195Y-39800D01*
X1117287Y-38925D01*
X1118815Y-38634D01*
X1119906Y-38925D01*
X1121217Y-39800D01*
G01X1139590Y-50300D02*
Y-38634D01*
G01Y-40675D02*
X1138717Y-39509D01*
X1137406Y-38925D01*
X1135878Y-38634D01*
X1134350Y-39217D01*
X1133040Y-40383D01*
X1132166Y-42133D01*
X1131730Y-44467D01*
X1132166Y-46800D01*
X1133040Y-48550D01*
X1134350Y-49717D01*
X1135878Y-50300D01*
X1137406Y-50008D01*
X1138717Y-49134D01*
X1139590Y-47967D01*
G01X1156653Y-40092D02*
X1155125Y-38925D01*
X1153815Y-38634D01*
X1152068Y-39217D01*
X1150758Y-40383D01*
X1149885Y-42425D01*
X1149666Y-44467D01*
X1149885Y-46509D01*
X1150758Y-48259D01*
X1152068Y-49717D01*
X1153815Y-50300D01*
X1155343Y-49717D01*
X1156653Y-48550D01*
G01X1167385Y-42425D02*
X1174372D01*
X1173717Y-40383D01*
X1172625Y-39217D01*
X1171097Y-38634D01*
X1169568Y-38925D01*
X1168258Y-39800D01*
X1167385Y-41842D01*
X1166948Y-43592D01*
Y-45342D01*
X1167385Y-47092D01*
X1168477Y-48842D01*
X1169787Y-50008D01*
X1171315Y-50300D01*
X1172843Y-49717D01*
X1174372Y-47967D01*
G01X1184885Y-48259D02*
X1185977Y-49425D01*
X1187505Y-50300D01*
X1188815D01*
X1190125Y-49717D01*
X1190998Y-48842D01*
X1191435Y-47676D01*
X1191217Y-45925D01*
X1190343Y-45050D01*
X1186413Y-43300D01*
X1185540Y-41258D01*
X1185977Y-39800D01*
X1186850Y-38925D01*
X1188160Y-38634D01*
X1189470Y-38925D01*
X1190780Y-39800D01*
G01X1223160Y-38634D02*
Y-50300D01*
G01Y-33967D02*
X1222723Y-33675D01*
Y-33092D01*
X1223160Y-32800D01*
X1223597Y-33092D01*
Y-33675D01*
X1223160Y-33967D01*
G01X1236948Y-50300D02*
Y-38634D01*
G01Y-41550D02*
X1237822Y-40092D01*
X1239132Y-38925D01*
X1240878Y-38634D01*
X1242406Y-38925D01*
X1243717Y-40092D01*
X1244372Y-42133D01*
Y-50300D01*
G01X1275660D02*
Y-32800D01*
G01X1297090Y-50300D02*
Y-38634D01*
G01Y-40675D02*
X1296217Y-39509D01*
X1294906Y-38925D01*
X1293378Y-38634D01*
X1291850Y-39217D01*
X1290540Y-40383D01*
X1289666Y-42133D01*
X1289230Y-44467D01*
X1289666Y-46800D01*
X1290540Y-48550D01*
X1291850Y-49717D01*
X1293378Y-50300D01*
X1294906Y-50008D01*
X1296217Y-49134D01*
X1297090Y-47967D01*
G01X1306075Y-55550D02*
X1307385Y-56133D01*
X1309132Y-55550D01*
X1310223Y-54384D01*
X1311097Y-52925D01*
X1312406Y-48259D01*
X1315245Y-38634D01*
G01X1308258D02*
X1312406Y-48259D01*
G01X1324885Y-42425D02*
X1331872D01*
X1331217Y-40383D01*
X1330125Y-39217D01*
X1328597Y-38634D01*
X1327068Y-38925D01*
X1325758Y-39800D01*
X1324885Y-41842D01*
X1324448Y-43592D01*
Y-45342D01*
X1324885Y-47092D01*
X1325977Y-48842D01*
X1327287Y-50008D01*
X1328815Y-50300D01*
X1330343Y-49717D01*
X1331872Y-47967D01*
G01X1342603Y-50300D02*
Y-38634D01*
G01Y-40967D02*
X1343695Y-39800D01*
X1344787Y-38925D01*
X1346315Y-38634D01*
X1347406Y-38925D01*
X1348717Y-39800D01*
G01X1376293Y-32800D02*
Y-50300D01*
X1385027D01*
G01X1398160D02*
Y-32800D01*
X1395540Y-36300D01*
G01Y-50300D02*
X1400780D01*
G01X1415660Y-50883D02*
X1415223Y-50592D01*
Y-50008D01*
X1415660Y-49717D01*
X1416097Y-50008D01*
Y-50592D01*
X1415660Y-50883D01*
G01X617008Y706896D02*
Y724396D01*
X621374D01*
X623121Y723521D01*
X624431Y722354D01*
X625523Y720605D01*
X626396Y718562D01*
X626614Y715646D01*
X626396Y712729D01*
X625523Y710687D01*
X624431Y708937D01*
X623121Y707771D01*
X621374Y706896D01*
X617008D01*
G01X634944D02*
Y724396D01*
X640184D01*
X641931Y723521D01*
X643241Y721479D01*
X643678Y719146D01*
X643241Y716813D01*
X642149Y715063D01*
X640184Y714187D01*
X634944D01*
G01X671691Y724396D02*
X676931D01*
G01X674311D02*
Y706896D01*
G01X671691D02*
X676931D01*
G01X686134D02*
Y724396D01*
X691811Y709813D01*
X697488Y724396D01*
Y706896D01*
G01X704944D02*
Y724396D01*
X710184D01*
X711931Y723521D01*
X713241Y721479D01*
X713678Y719146D01*
X713241Y716813D01*
X712149Y715063D01*
X710184Y714187D01*
X704944D01*
G01X731178Y706896D02*
X722444D01*
Y724396D01*
X731178D01*
G01X727684Y715938D02*
X722444D01*
G01X739508Y706896D02*
Y724396D01*
X743874D01*
X745621Y723521D01*
X746931Y722354D01*
X748023Y720605D01*
X748896Y718562D01*
X749114Y715646D01*
X748896Y712729D01*
X748023Y710687D01*
X746931Y708937D01*
X745621Y707771D01*
X743874Y706896D01*
X739508D01*
G01X756352D02*
X761811Y724396D01*
X767270Y706896D01*
G01X765304Y713021D02*
X758317D01*
G01X774289Y706896D02*
Y724396D01*
X784333Y706896D01*
Y724396D01*
G01X801614Y722937D02*
X800304Y723813D01*
X798776Y724396D01*
X797029D01*
X795064Y723521D01*
X793536Y722063D01*
X792444Y720312D01*
X791571Y717396D01*
X791352Y714771D01*
X791789Y712146D01*
X792444Y710396D01*
X793754Y708646D01*
X795283Y707479D01*
X796811Y706896D01*
X798339D01*
X799868Y707479D01*
X801178Y708354D01*
X802270Y709520D01*
G01X818678Y706896D02*
X809944D01*
Y724396D01*
X818678D01*
G01X815184Y715938D02*
X809944D01*
G01X849311Y724396D02*
Y706896D01*
G01X844289Y724396D02*
X854333D01*
G01X861352Y706896D02*
X866811Y724396D01*
X872270Y706896D01*
G01X870304Y713021D02*
X863317D01*
G01X886057Y716229D02*
X886931Y717104D01*
X887586Y718562D01*
X888023Y720605D01*
X887586Y722354D01*
X886713Y723521D01*
X885184Y724396D01*
X879289D01*
Y706896D01*
X886494D01*
X888023Y708062D01*
X888896Y709813D01*
X889333Y711854D01*
X888896Y713896D01*
X887586Y715646D01*
X886057Y716229D01*
X879289D01*
G01X897444Y724396D02*
Y706896D01*
X906178D01*
G01X923678D02*
X914944D01*
Y724396D01*
X923678D01*
G01X920184Y715938D02*
X914944D01*
G01X936811Y706313D02*
X936374Y706604D01*
Y707188D01*
X936811Y707479D01*
X937248Y707188D01*
Y706604D01*
X936811Y706313D01*
G01Y714187D02*
X936374Y714479D01*
Y715063D01*
X936811Y715354D01*
X937248Y715063D01*
Y714479D01*
X936811Y714187D01*
G01X967444Y724396D02*
Y706896D01*
X976178D01*
G01X989311D02*
Y724396D01*
X986691Y720896D01*
G01Y706896D02*
X991931D01*
G01X638891Y689746D02*
X644131D01*
G01X641511D02*
Y672246D01*
G01X638891D02*
X644131D01*
G01X653334D02*
Y689746D01*
X659011Y675163D01*
X664688Y689746D01*
Y672246D01*
G01X672144D02*
Y689746D01*
X677384D01*
X679131Y688871D01*
X680441Y686829D01*
X680878Y684496D01*
X680441Y682163D01*
X679349Y680413D01*
X677384Y679537D01*
X672144D01*
G01X692919Y666413D02*
X690736Y669329D01*
X689644Y672246D01*
Y683912D01*
X690736Y686829D01*
X692919Y689746D01*
G01X711511Y672246D02*
X709764Y672538D01*
X708236Y673704D01*
X706926Y675454D01*
X706052Y677496D01*
X705616Y679829D01*
Y682163D01*
X706052Y684496D01*
X706926Y686538D01*
X708236Y688287D01*
X709764Y689454D01*
X711511Y689746D01*
X713257Y689454D01*
X714786Y688287D01*
X716096Y686538D01*
X716970Y684496D01*
X717406Y682163D01*
Y679829D01*
X716970Y677496D01*
X716096Y675454D01*
X714786Y673704D01*
X713257Y672538D01*
X711511Y672246D01*
G01X725299D02*
Y689746D01*
G01Y681288D02*
X726391Y682746D01*
X727483Y683621D01*
X729229Y683912D01*
X730539Y683621D01*
X732068Y682454D01*
X732723Y680704D01*
Y672246D01*
G01X739961D02*
Y683912D01*
G01Y680704D02*
X740616Y682163D01*
X741708Y683329D01*
X743236Y683912D01*
X744764Y683329D01*
X745856Y682163D01*
X746511Y680704D01*
Y672246D01*
G01Y680704D02*
X747166Y682163D01*
X748257Y683329D01*
X749786Y683912D01*
X751314Y683329D01*
X752406Y682163D01*
X753061Y680413D01*
Y672246D01*
G01X765103Y666413D02*
X767286Y669329D01*
X768378Y672246D01*
Y683912D01*
X767286Y686829D01*
X765103Y689746D01*
G01X676511Y637596D02*
X678039Y637888D01*
X679786Y638762D01*
X680878Y640220D01*
X681314Y642263D01*
X680878Y644304D01*
X679568Y646054D01*
X677603Y646929D01*
X675419D01*
X674109Y647513D01*
X673017Y648971D01*
X672581Y651012D01*
X673236Y653054D01*
X674764Y654513D01*
X676511Y655096D01*
X678257Y654513D01*
X679786Y653054D01*
X680441Y651012D01*
X680004Y648971D01*
X678913Y647513D01*
X677603Y646929D01*
X675419D01*
X673454Y646054D01*
X672144Y644304D01*
X671708Y642263D01*
X672144Y640220D01*
X673236Y638762D01*
X674983Y637888D01*
X676511Y637596D01*
G01X689208Y640220D02*
X690517Y638762D01*
X692046Y637888D01*
X694011Y637596D01*
X695976Y638179D01*
X697504Y639346D01*
X698596Y641387D01*
X698814Y643721D01*
X698378Y646054D01*
X697286Y647513D01*
X695757Y648679D01*
X694229Y648971D01*
X692701Y648679D01*
X690736Y647513D01*
X691391Y655096D01*
X697286D01*
G01X711511Y637013D02*
X711074Y637304D01*
Y637888D01*
X711511Y638179D01*
X711948Y637888D01*
Y637304D01*
X711511Y637013D01*
G01X729011Y655096D02*
X727264Y654513D01*
X725954Y653054D01*
X725081Y651305D01*
X724426Y648971D01*
X724208Y646346D01*
X724426Y643721D01*
X725081Y641387D01*
X725954Y639637D01*
X727264Y638179D01*
X729011Y637596D01*
X730757Y638179D01*
X732068Y639637D01*
X732941Y641387D01*
X733596Y643721D01*
X733814Y646346D01*
X733596Y648971D01*
X732941Y651305D01*
X732068Y653054D01*
X730757Y654513D01*
X729011Y655096D01*
G01X818711Y689746D02*
X821767Y672246D01*
X825261Y689746D01*
X828754Y672246D01*
X831811Y689746D01*
G01X840141D02*
X845381D01*
G01X842761D02*
Y672246D01*
G01X840141D02*
X845381D01*
G01X855458D02*
Y689746D01*
X859824D01*
X861571Y688871D01*
X862881Y687704D01*
X863973Y685955D01*
X864846Y683912D01*
X865064Y680996D01*
X864846Y678079D01*
X863973Y676037D01*
X862881Y674287D01*
X861571Y673121D01*
X859824Y672246D01*
X855458D01*
G01X877761Y689746D02*
Y672246D01*
G01X872739Y689746D02*
X882783D01*
G01X890676Y672246D02*
Y689746D01*
G01X899846D02*
Y672246D01*
G01Y680996D02*
X890676D01*
G01X911669Y666413D02*
X909486Y669329D01*
X908394Y672246D01*
Y683912D01*
X909486Y686829D01*
X911669Y689746D01*
G01X923711Y672246D02*
Y683912D01*
G01Y680704D02*
X924366Y682163D01*
X925458Y683329D01*
X926986Y683912D01*
X928514Y683329D01*
X929606Y682163D01*
X930261Y680704D01*
Y672246D01*
G01Y680704D02*
X930916Y682163D01*
X932007Y683329D01*
X933536Y683912D01*
X935064Y683329D01*
X936156Y682163D01*
X936811Y680413D01*
Y672246D01*
G01X947761Y683912D02*
Y672246D01*
G01Y688579D02*
X947324Y688871D01*
Y689454D01*
X947761Y689746D01*
X948198Y689454D01*
Y688871D01*
X947761Y688579D01*
G01X965261Y672246D02*
Y689746D01*
G01X979486Y674287D02*
X980578Y673121D01*
X982106Y672246D01*
X983416D01*
X984726Y672829D01*
X985599Y673704D01*
X986036Y674870D01*
X985818Y676621D01*
X984944Y677496D01*
X981014Y679246D01*
X980141Y681288D01*
X980578Y682746D01*
X981451Y683621D01*
X982761Y683912D01*
X984071Y683621D01*
X985381Y682746D01*
G01X1001353Y666413D02*
X1003536Y669329D01*
X1004628Y672246D01*
Y683912D01*
X1003536Y686829D01*
X1001353Y689746D01*
G01X860261Y637596D02*
X861789Y637888D01*
X863536Y638762D01*
X864628Y640220D01*
X865064Y642263D01*
X864628Y644304D01*
X863318Y646054D01*
X861353Y646929D01*
X859169D01*
X857859Y647513D01*
X856767Y648971D01*
X856331Y651012D01*
X856986Y653054D01*
X858514Y654513D01*
X860261Y655096D01*
X862007Y654513D01*
X863536Y653054D01*
X864191Y651012D01*
X863754Y648971D01*
X862663Y647513D01*
X861353Y646929D01*
X859169D01*
X857204Y646054D01*
X855894Y644304D01*
X855458Y642263D01*
X855894Y640220D01*
X856986Y638762D01*
X858733Y637888D01*
X860261Y637596D01*
G01X877761Y637013D02*
X877324Y637304D01*
Y637888D01*
X877761Y638179D01*
X878198Y637888D01*
Y637304D01*
X877761Y637013D01*
G01X897881Y637596D02*
Y655096D01*
X889802Y642554D01*
X900720D01*
G01X908831Y637013D02*
X916691Y655096D01*
G01X926549Y639637D02*
X928078Y638179D01*
X929824Y637596D01*
X931571Y638179D01*
X933099Y639929D01*
X934191Y642554D01*
X934628Y645179D01*
Y648387D01*
X934191Y651012D01*
X933099Y653346D01*
X931789Y654513D01*
X930261Y655096D01*
X928514Y654513D01*
X927204Y653346D01*
X926331Y651596D01*
X925894Y649262D01*
X926331Y647221D01*
X927423Y645179D01*
X928733Y644012D01*
X930261Y643721D01*
X932007Y644304D01*
X933318Y645763D01*
X934628Y648387D01*
G01X947761Y637013D02*
X947324Y637304D01*
Y637888D01*
X947761Y638179D01*
X948198Y637888D01*
Y637304D01*
X947761Y637013D01*
G01X965261Y655096D02*
X963514Y654513D01*
X962204Y653054D01*
X961331Y651305D01*
X960676Y648971D01*
X960458Y646346D01*
X960676Y643721D01*
X961331Y641387D01*
X962204Y639637D01*
X963514Y638179D01*
X965261Y637596D01*
X967007Y638179D01*
X968318Y639637D01*
X969191Y641387D01*
X969846Y643721D01*
X970064Y646346D01*
X969846Y648971D01*
X969191Y651305D01*
X968318Y653054D01*
X967007Y654513D01*
X965261Y655096D01*
G01X1061511Y689746D02*
Y672246D01*
G01X1056489Y689746D02*
X1066533D01*
G01X1079011Y672246D02*
Y680121D01*
X1074644Y689746D01*
G01X1083378D02*
X1079011Y680121D01*
G01X1092144Y672246D02*
Y689746D01*
X1097384D01*
X1099131Y688871D01*
X1100441Y686829D01*
X1100878Y684496D01*
X1100441Y682163D01*
X1099349Y680413D01*
X1097384Y679537D01*
X1092144D01*
G01X1118378Y672246D02*
X1109644D01*
Y689746D01*
X1118378D01*
G01X1114884Y681288D02*
X1109644D01*
G01X1074208Y637596D02*
Y655096D01*
X1078574D01*
X1080321Y654221D01*
X1081631Y653054D01*
X1082723Y651305D01*
X1083596Y649262D01*
X1083814Y646346D01*
X1083596Y643429D01*
X1082723Y641387D01*
X1081631Y639637D01*
X1080321Y638471D01*
X1078574Y637596D01*
X1074208D01*
G01X1092144D02*
Y655096D01*
X1097384D01*
X1099131Y654221D01*
X1100441Y652179D01*
X1100878Y649846D01*
X1100441Y647513D01*
X1099349Y645763D01*
X1097384Y644887D01*
X1092144D01*
G01X1162144Y672246D02*
Y689746D01*
X1167603D01*
X1169349Y688871D01*
X1170441Y687704D01*
X1170878Y685371D01*
X1170441Y683037D01*
X1169131Y681579D01*
X1167603Y680704D01*
X1162144D01*
G01X1167603D02*
X1170878Y672246D01*
G01X1180736Y680121D02*
X1187723D01*
X1187068Y682163D01*
X1185976Y683329D01*
X1184448Y683912D01*
X1182919Y683621D01*
X1181609Y682746D01*
X1180736Y680704D01*
X1180299Y678954D01*
Y677204D01*
X1180736Y675454D01*
X1181828Y673704D01*
X1183138Y672538D01*
X1184666Y672246D01*
X1186194Y672829D01*
X1187723Y674579D01*
G01X1200201Y672246D02*
Y687121D01*
X1200638Y688579D01*
X1201511Y689454D01*
X1202821Y689746D01*
X1204131Y689163D01*
X1204786Y687704D01*
G01X1202166Y682746D02*
X1197799D01*
G01X1219011Y671663D02*
X1218574Y671954D01*
Y672538D01*
X1219011Y672829D01*
X1219448Y672538D01*
Y671954D01*
X1219011Y671663D01*
G01X1249644Y672246D02*
Y689746D01*
X1254884D01*
X1256631Y688871D01*
X1257941Y686829D01*
X1258378Y684496D01*
X1257941Y682163D01*
X1256849Y680413D01*
X1254884Y679537D01*
X1249644D01*
G01X1271511Y672246D02*
Y689746D01*
G01X1292941Y672246D02*
Y683912D01*
G01Y681871D02*
X1292068Y683037D01*
X1290757Y683621D01*
X1289229Y683912D01*
X1287701Y683329D01*
X1286391Y682163D01*
X1285517Y680413D01*
X1285081Y678079D01*
X1285517Y675746D01*
X1286391Y673996D01*
X1287701Y672829D01*
X1289229Y672246D01*
X1290757Y672538D01*
X1292068Y673412D01*
X1292941Y674579D01*
G01X1302799Y672246D02*
Y683912D01*
G01Y680996D02*
X1303673Y682454D01*
X1304983Y683621D01*
X1306729Y683912D01*
X1308257Y683621D01*
X1309568Y682454D01*
X1310223Y680413D01*
Y672246D01*
G01X1320736Y680121D02*
X1327723D01*
X1327068Y682163D01*
X1325976Y683329D01*
X1324448Y683912D01*
X1322919Y683621D01*
X1321609Y682746D01*
X1320736Y680704D01*
X1320299Y678954D01*
Y677204D01*
X1320736Y675454D01*
X1321828Y673704D01*
X1323138Y672538D01*
X1324666Y672246D01*
X1326194Y672829D01*
X1327723Y674579D01*
G01X1232144Y655096D02*
Y637596D01*
X1240878D01*
G01X1249863Y652179D02*
X1251173Y653929D01*
X1252701Y654804D01*
X1254448Y655096D01*
X1256631Y654513D01*
X1258159Y653054D01*
X1258596Y651305D01*
X1258378Y649554D01*
X1257504Y648096D01*
X1253138Y645179D01*
X1251173Y643138D01*
X1249863Y640220D01*
X1249426Y637596D01*
X1258596D01*
G01X1441811Y649262D02*
Y637596D01*
G01Y653929D02*
X1441374Y654221D01*
Y654804D01*
X1441811Y655096D01*
X1442248Y654804D01*
Y654221D01*
X1441811Y653929D01*
G01X1456036Y639637D02*
X1457128Y638471D01*
X1458656Y637596D01*
X1459966D01*
X1461276Y638179D01*
X1462149Y639054D01*
X1462586Y640220D01*
X1462368Y641971D01*
X1461494Y642846D01*
X1457564Y644596D01*
X1456691Y646638D01*
X1457128Y648096D01*
X1458001Y648971D01*
X1459311Y649262D01*
X1460621Y648971D01*
X1461931Y648096D01*
G01X1489289Y637596D02*
Y655096D01*
X1499333Y637596D01*
Y655096D01*
G01X1511811Y637596D02*
X1510064Y637888D01*
X1508536Y639054D01*
X1507226Y640804D01*
X1506352Y642846D01*
X1505916Y645179D01*
Y647513D01*
X1506352Y649846D01*
X1507226Y651888D01*
X1508536Y653637D01*
X1510064Y654804D01*
X1511811Y655096D01*
X1513557Y654804D01*
X1515086Y653637D01*
X1516396Y651888D01*
X1517270Y649846D01*
X1517706Y647513D01*
Y645179D01*
X1517270Y642846D01*
X1516396Y640804D01*
X1515086Y639054D01*
X1513557Y637888D01*
X1511811Y637596D01*
G01X1529311Y655096D02*
Y637596D01*
G01X1524289Y655096D02*
X1534333D01*
G01X1560599Y649262D02*
Y641096D01*
X1561473Y639054D01*
X1562783Y637888D01*
X1564311Y637596D01*
X1565839Y637888D01*
X1567149Y639054D01*
X1568023Y641096D01*
G01Y637596D02*
Y649262D01*
G01X1578536Y639637D02*
X1579628Y638471D01*
X1581156Y637596D01*
X1582466D01*
X1583776Y638179D01*
X1584649Y639054D01*
X1585086Y640220D01*
X1584868Y641971D01*
X1583994Y642846D01*
X1580064Y644596D01*
X1579191Y646638D01*
X1579628Y648096D01*
X1580501Y648971D01*
X1581811Y649262D01*
X1583121Y648971D01*
X1584431Y648096D01*
G01X1596036Y645471D02*
X1603023D01*
X1602368Y647513D01*
X1601276Y648679D01*
X1599748Y649262D01*
X1598219Y648971D01*
X1596909Y648096D01*
X1596036Y646054D01*
X1595599Y644304D01*
Y642554D01*
X1596036Y640804D01*
X1597128Y639054D01*
X1598438Y637888D01*
X1599966Y637596D01*
X1601494Y638179D01*
X1603023Y639929D01*
G01X1620741Y655096D02*
Y637596D01*
G01Y640220D02*
X1619868Y638762D01*
X1618557Y637888D01*
X1617029Y637596D01*
X1615283Y638179D01*
X1613973Y639637D01*
X1613099Y641387D01*
X1612881Y643429D01*
X1613099Y645471D01*
X1613973Y647221D01*
X1615283Y648679D01*
X1617029Y649262D01*
X1618557Y648971D01*
X1619649Y648387D01*
X1620741Y647221D01*
G01X1367008Y671663D02*
X1376614Y684496D01*
G01X1371811Y686829D02*
Y669329D01*
G01X1376614Y671663D02*
X1367008Y684496D01*
G01X1365261Y678079D02*
X1378361D01*
G01X1403973D02*
X1409649D01*
G01X1437008Y672246D02*
Y689746D01*
X1441374D01*
X1443121Y688871D01*
X1444431Y687704D01*
X1445523Y685955D01*
X1446396Y683912D01*
X1446614Y680996D01*
X1446396Y678079D01*
X1445523Y676037D01*
X1444431Y674287D01*
X1443121Y673121D01*
X1441374Y672246D01*
X1437008D01*
G01X1456036Y680121D02*
X1463023D01*
X1462368Y682163D01*
X1461276Y683329D01*
X1459748Y683912D01*
X1458219Y683621D01*
X1456909Y682746D01*
X1456036Y680704D01*
X1455599Y678954D01*
Y677204D01*
X1456036Y675454D01*
X1457128Y673704D01*
X1458438Y672538D01*
X1459966Y672246D01*
X1461494Y672829D01*
X1463023Y674579D01*
G01X1473099Y672246D02*
Y683912D01*
G01Y680996D02*
X1473973Y682454D01*
X1475283Y683621D01*
X1477029Y683912D01*
X1478557Y683621D01*
X1479868Y682454D01*
X1480523Y680413D01*
Y672246D01*
G01X1494311D02*
X1493001Y672538D01*
X1491691Y673704D01*
X1490817Y675746D01*
X1490381Y678079D01*
X1490817Y680413D01*
X1491691Y682454D01*
X1493001Y683621D01*
X1494311Y683912D01*
X1495621Y683621D01*
X1496931Y682454D01*
X1497804Y680413D01*
X1498023Y678079D01*
X1497804Y675746D01*
X1496931Y673704D01*
X1495621Y672538D01*
X1494311Y672246D01*
G01X1511811Y689746D02*
Y672246D01*
G01X1508754Y683912D02*
X1514868D01*
G01X1526036Y680121D02*
X1533023D01*
X1532368Y682163D01*
X1531276Y683329D01*
X1529748Y683912D01*
X1528219Y683621D01*
X1526909Y682746D01*
X1526036Y680704D01*
X1525599Y678954D01*
Y677204D01*
X1526036Y675454D01*
X1527128Y673704D01*
X1528438Y672538D01*
X1529966Y672246D01*
X1531494Y672829D01*
X1533023Y674579D01*
G01X1543536Y674287D02*
X1544628Y673121D01*
X1546156Y672246D01*
X1547466D01*
X1548776Y672829D01*
X1549649Y673704D01*
X1550086Y674870D01*
X1549868Y676621D01*
X1548994Y677496D01*
X1545064Y679246D01*
X1544191Y681288D01*
X1544628Y682746D01*
X1545501Y683621D01*
X1546811Y683912D01*
X1548121Y683621D01*
X1549431Y682746D01*
G01X1581811Y689746D02*
Y672246D01*
G01X1578754Y683912D02*
X1584868D01*
G01X1595599Y672246D02*
Y689746D01*
G01Y681288D02*
X1596691Y682746D01*
X1597783Y683621D01*
X1599529Y683912D01*
X1600839Y683621D01*
X1602368Y682454D01*
X1603023Y680704D01*
Y672246D01*
G01X1620741D02*
Y683912D01*
G01Y681871D02*
X1619868Y683037D01*
X1618557Y683621D01*
X1617029Y683912D01*
X1615501Y683329D01*
X1614191Y682163D01*
X1613317Y680413D01*
X1612881Y678079D01*
X1613317Y675746D01*
X1614191Y673996D01*
X1615501Y672829D01*
X1617029Y672246D01*
X1618557Y672538D01*
X1619868Y673412D01*
X1620741Y674579D01*
G01X1634311Y689746D02*
Y672246D01*
G01X1631254Y683912D02*
X1637368D01*
G01X1669311Y689746D02*
Y672246D01*
G01X1666254Y683912D02*
X1672368D01*
G01X1683099Y672246D02*
Y689746D01*
G01Y681288D02*
X1684191Y682746D01*
X1685283Y683621D01*
X1687029Y683912D01*
X1688339Y683621D01*
X1689868Y682454D01*
X1690523Y680704D01*
Y672246D01*
G01X1704311Y683912D02*
Y672246D01*
G01Y688579D02*
X1703874Y688871D01*
Y689454D01*
X1704311Y689746D01*
X1704748Y689454D01*
Y688871D01*
X1704311Y688579D01*
G01X1718536Y674287D02*
X1719628Y673121D01*
X1721156Y672246D01*
X1722466D01*
X1723776Y672829D01*
X1724649Y673704D01*
X1725086Y674870D01*
X1724868Y676621D01*
X1723994Y677496D01*
X1720064Y679246D01*
X1719191Y681288D01*
X1719628Y682746D01*
X1720501Y683621D01*
X1721811Y683912D01*
X1723121Y683621D01*
X1724431Y682746D01*
G01X1754191Y689746D02*
X1759431D01*
G01X1756811D02*
Y672246D01*
G01X1754191D02*
X1759431D01*
G01X1767761D02*
Y683912D01*
G01Y680704D02*
X1768416Y682163D01*
X1769508Y683329D01*
X1771036Y683912D01*
X1772564Y683329D01*
X1773656Y682163D01*
X1774311Y680704D01*
Y672246D01*
G01Y680704D02*
X1774966Y682163D01*
X1776057Y683329D01*
X1777586Y683912D01*
X1779114Y683329D01*
X1780206Y682163D01*
X1780861Y680413D01*
Y672246D01*
G01X1787881Y666413D02*
Y683912D01*
G01Y681288D02*
X1788973Y682746D01*
X1790064Y683621D01*
X1791811Y683912D01*
X1793339Y683621D01*
X1794868Y682163D01*
X1795523Y680121D01*
X1795741Y678079D01*
X1795523Y676037D01*
X1794868Y673996D01*
X1793557Y672829D01*
X1791811Y672246D01*
X1790283Y672538D01*
X1788754Y673412D01*
X1787881Y674579D01*
G01X1806036Y680121D02*
X1813023D01*
X1812368Y682163D01*
X1811276Y683329D01*
X1809748Y683912D01*
X1808219Y683621D01*
X1806909Y682746D01*
X1806036Y680704D01*
X1805599Y678954D01*
Y677204D01*
X1806036Y675454D01*
X1807128Y673704D01*
X1808438Y672538D01*
X1809966Y672246D01*
X1811494Y672829D01*
X1813023Y674579D01*
G01X1830741Y689746D02*
Y672246D01*
G01Y674870D02*
X1829868Y673412D01*
X1828557Y672538D01*
X1827029Y672246D01*
X1825283Y672829D01*
X1823973Y674287D01*
X1823099Y676037D01*
X1822881Y678079D01*
X1823099Y680121D01*
X1823973Y681871D01*
X1825283Y683329D01*
X1827029Y683912D01*
X1828557Y683621D01*
X1829649Y683037D01*
X1830741Y681871D01*
G01X1848241Y672246D02*
Y683912D01*
G01Y681871D02*
X1847368Y683037D01*
X1846057Y683621D01*
X1844529Y683912D01*
X1843001Y683329D01*
X1841691Y682163D01*
X1840817Y680413D01*
X1840381Y678079D01*
X1840817Y675746D01*
X1841691Y673996D01*
X1843001Y672829D01*
X1844529Y672246D01*
X1846057Y672538D01*
X1847368Y673412D01*
X1848241Y674579D01*
G01X1858099Y672246D02*
Y683912D01*
G01Y680996D02*
X1858973Y682454D01*
X1860283Y683621D01*
X1862029Y683912D01*
X1863557Y683621D01*
X1864868Y682454D01*
X1865523Y680413D01*
Y672246D01*
G01X1882804Y682454D02*
X1881276Y683621D01*
X1879966Y683912D01*
X1878219Y683329D01*
X1876909Y682163D01*
X1876036Y680121D01*
X1875817Y678079D01*
X1876036Y676037D01*
X1876909Y674287D01*
X1878219Y672829D01*
X1879966Y672246D01*
X1881494Y672829D01*
X1882804Y673996D01*
G01X1893536Y680121D02*
X1900523D01*
X1899868Y682163D01*
X1898776Y683329D01*
X1897248Y683912D01*
X1895719Y683621D01*
X1894409Y682746D01*
X1893536Y680704D01*
X1893099Y678954D01*
Y677204D01*
X1893536Y675454D01*
X1894628Y673704D01*
X1895938Y672538D01*
X1897466Y672246D01*
X1898994Y672829D01*
X1900523Y674579D01*
G01X-25590Y9843D02*
G03X-15748Y0I9842J-1D01*
G01X-25590Y89370D02*
Y9843D01*
G01X-23622Y91339D02*
G03X-25590Y89370I1J-1969D01*
G01X-7874Y91339D02*
X-23622D01*
G01X-25590Y109055D02*
G03X-21653Y105118I3937J0D01*
G01X-25590Y357874D02*
Y109055D01*
G01X-21653Y105118D02*
X261811D01*
G01X-25590Y371654D02*
G03X-23622Y369685I1968J-1D01*
G01X-21653Y361811D02*
G03X-25590Y357874I0J-3937D01*
G01X1969Y361811D02*
X-21653D01*
G01X-7874Y369685D02*
X-23622D01*
G01X-25590Y459055D02*
Y371654D01*
G01X-23622Y461024D02*
G03X-25590Y459055I1J-1969D01*
G01X-7874Y461024D02*
X-23622D01*
G01X-25590Y478740D02*
G03X-21653Y474803I3937J0D01*
G01X-25590Y727559D02*
Y478740D01*
G01X-21653Y474803D02*
X261811D01*
G01X-21653Y731496D02*
G03X-25590Y727559I0J-3937D01*
G01X1969Y731496D02*
X-21653D01*
G01X-11811Y0D02*
G03X-7874Y3937I0J3937D01*
G01X-11811Y0D02*
X-15748D01*
G01X0Y3937D02*
G03X3937Y0I3937J0D01*
G01X-7874Y33071D02*
Y3937D01*
G01X0Y87402D02*
Y3937D01*
G01Y33071D02*
G03X-7874I-3937J0D01*
G01Y58268D02*
G03X0I3937J0D01*
G01X-7874Y91339D02*
Y58268D01*
G01X3937Y91339D02*
G03X0Y87402I0J-3937D01*
G01X5906Y357874D02*
G03X1969Y361811I-3937J0D01*
G01X0Y373622D02*
G03X3937Y369685I3937J0D01*
G01X-7874Y402756D02*
Y369685D01*
G01X0Y457087D02*
Y373622D01*
G01Y402756D02*
G03X-7874I-3937J0D01*
G01Y427953D02*
G03X0I3937J0D01*
G01X-7874Y461024D02*
Y427953D01*
G01X3937Y461024D02*
G03X0Y457087I0J-3937D01*
G01X5906Y727559D02*
G03X1969Y731496I-3937J0D01*
G01X3937Y0D02*
X372048D01*
G01X192914Y91339D02*
X3937D01*
G01X5906Y290748D02*
G03X9843Y286811I3937J0D01*
G01X5906Y357874D02*
Y290748D01*
G01X69488Y286811D02*
X9843D01*
G01X13780Y315650D02*
Y294685D01*
G01X69488D02*
X13780D01*
G01Y315650D02*
G03X5906I-3937J0D01*
G01Y340847D02*
G03X13780I3937J0D01*
G01Y361811D02*
Y340847D01*
G01X3937Y369685D02*
X372048D01*
G01X43307Y361811D02*
X13780D01*
G01X192914Y461024D02*
X3937D01*
G01X5906Y660433D02*
G03X9843Y656496I3937J0D01*
G01X5906Y727559D02*
Y660433D01*
G01X69488Y656496D02*
X9843D01*
G01X13780Y685335D02*
Y664370D01*
G01X69488D02*
X13780D01*
G01Y685335D02*
G03X5906I-3937J0D01*
G01Y710532D02*
G03X13780I3937J0D01*
G01Y729528D02*
Y710532D01*
G01X15748Y731496D02*
G03X13780Y729528I0J-1968D01*
G01X44819Y731496D02*
X15748D01*
G01X43307Y361811D02*
G03Y369685I0J3937D01*
G01X46675Y730184D02*
G03X44819Y731496I-1856J-657D01*
G01X46675Y730184D02*
G03X54098I3712J1313D01*
G01X53150Y181697D02*
G03X55118Y179729I1968J0D01*
G01X53150Y195477D02*
Y181697D01*
G01X55118Y179729D02*
X161418D01*
G01X55118Y197445D02*
G03X53150Y195477I0J-1968D01*
G01X161418Y197445D02*
X55118D01*
G01X73426Y282874D02*
G03X69488Y286811I-3937J0D01*
G01X81300Y282874D02*
G03X69488Y294685I-11811J0D01*
G01X74016Y369685D02*
G03Y361811I0J-3937D01*
G01X53150Y551382D02*
G03X55118Y549414I1968J0D01*
G01X53150Y565162D02*
Y551382D01*
G01X55118Y549414D02*
X161418D01*
G01X55118Y567130D02*
G03X53150Y565162I0J-1968D01*
G01X161418Y567130D02*
X55118D01*
G01X73426Y652559D02*
G03X69488Y656496I-3937J0D01*
G01X81300Y652559D02*
G03X69488Y664370I-11811J0D01*
G01X55954Y731496D02*
G03X54098Y730184I0J-1969D01*
G01X153544Y731496D02*
X55954D01*
G01X80709Y43307D02*
G03X82677Y41339I1968J0D01*
G01Y47244D02*
G03X80709Y45276I0J-1968D01*
G01X188977Y47244D02*
X82677D01*
G01Y41339D02*
X188977D01*
G01X80709Y45276D02*
Y43307D01*
G01X86614Y101181D02*
G03X82677Y105118I-3937J0D01*
G01X86614Y95276D02*
Y101181D01*
G01X82677Y91339D02*
G03X86614Y95276I0J3937D01*
G01X73426Y267323D02*
G03X77363Y263386I3937J0D01*
G01X73426Y267323D02*
Y282874D01*
G01X77363Y263386D02*
X159449D01*
G01X81300Y271260D02*
Y282874D01*
G01Y271260D02*
X155512D01*
G01Y361811D02*
X74016D01*
G01X80709Y412992D02*
G03X82677Y411024I1968J0D01*
G01Y416929D02*
G03X80709Y414961I0J-1968D01*
G01X188977Y416929D02*
X82677D01*
G01Y411024D02*
X188977D01*
G01X80709Y414961D02*
Y412992D01*
G01X86614Y464961D02*
Y470866D01*
G01X82677Y461024D02*
G03X86614Y464961I0J3937D01*
G01Y470866D02*
G03X82677Y474803I-3937J0D01*
G01X73426Y637008D02*
G03X77363Y633071I3937J0D01*
G01X73426Y637008D02*
Y652559D01*
G01X77363Y633071D02*
X159449D01*
G01X81300Y640945D02*
Y652559D01*
G01Y640945D02*
X155512D01*
G01X109449Y95276D02*
Y101181D01*
G01X113386Y105118D02*
G03X109449Y101181I0J-3937D01*
G01Y95276D02*
G03X113386Y91339I3937J0D01*
G01X109449Y464961D02*
Y470866D01*
G01Y464961D02*
G03X113386Y461024I3937J0D01*
G01Y474803D02*
G03X109449Y470866I0J-3937D01*
G01X161418Y179729D02*
G03X163386Y181697I0J1968D01*
G01Y195477D02*
G03X161418Y197445I-1968J0D01*
G01X159449Y263386D02*
G03X163386Y267323I0J3937D01*
G01X155512Y303937D02*
Y271260D01*
G01X163386Y303937D02*
G03X155512I-3937J0D01*
G01Y329134D02*
G03X163386I3937J0D01*
G01X155512Y361811D02*
Y329134D01*
G01X161418Y549414D02*
G03X163386Y551382I0J1968D01*
G01Y565162D02*
G03X161418Y567130I-1968J0D01*
G01X159449Y633071D02*
G03X163386Y637008I0J3937D01*
G01X155512Y673622D02*
Y640945D01*
G01X163386Y673622D02*
G03X155512I-3937J0D01*
G01Y698819D02*
G03X163386I3937J0D01*
G01X155512Y729528D02*
Y698819D01*
G01Y729528D02*
G03X153544Y731496I-1968J0D01*
G01X163386Y181697D02*
Y195477D01*
G01Y357874D02*
Y267323D01*
G01X167323Y361811D02*
G03X163386Y357874I0J-3937D01*
G01X535433Y361811D02*
X167323D01*
G01X163386Y551382D02*
Y565162D01*
G01Y727559D02*
Y637008D01*
G01X167323Y731496D02*
G03X163386Y727559I0J-3937D01*
G01X535433Y731496D02*
X167323D01*
G01X188977Y41339D02*
G03X190945Y43307I0J1968D01*
G01Y45276D02*
G03X188977Y47244I-1968J0D01*
G01X190945Y43307D02*
Y45276D01*
G01X196851Y97244D02*
G03X194882Y95276I0J-1969D01*
G01X192914Y91339D02*
G03X194882Y93307I0J1968D01*
G01X196851Y97244D02*
X269685D01*
G01X194882Y93307D02*
Y95276D01*
G01X188977Y411024D02*
G03X190945Y412992I0J1968D01*
G01Y414961D02*
G03X188977Y416929I-1968J0D01*
G01X190945Y412992D02*
Y414961D01*
G01X196851Y466929D02*
G03X194882Y464961I-1J-1968D01*
G01X192914Y461024D02*
G03X194882Y462992I0J1968D01*
G01D02*
Y464961D01*
G01X196851Y466929D02*
X269685D01*
G01Y97244D02*
G03X273622Y101181I0J3937D01*
G01Y252756D02*
Y101181D01*
G01X261811Y105118D02*
G03X265748Y109055I0J3937D01*
G01D02*
Y260630D01*
G01X273622Y165551D02*
G03X265748I-3937J0D01*
G01Y196260D02*
G03X273622I3937J0D01*
G01X269685Y264567D02*
G03X265748Y260630I0J-3937D01*
G01X277559Y256693D02*
G03X273622Y252756I0J-3937D01*
G01X342520Y264567D02*
X269685D01*
G01X254331Y361811D02*
G03Y369685I0J3937D01*
G01X261811Y474803D02*
G03X265748Y478740I0J3937D01*
G01D02*
Y630315D01*
G01X269685Y466929D02*
G03X273622Y470866I0J3937D01*
G01Y622441D02*
Y470866D01*
G01Y535236D02*
G03X265748I-3937J0D01*
G01Y565945D02*
G03X273622I3937J0D01*
G01X277559Y626378D02*
G03X273622Y622441I0J-3937D01*
G01X269685Y634252D02*
G03X265748Y630315I0J-3937D01*
G01X342520Y634252D02*
X269685D01*
G01X561024Y256693D02*
X277559D01*
G01X285040Y369685D02*
G03Y361811I0J-3937D01*
G01X561024Y626378D02*
X277559D01*
G01X342520Y264567D02*
G03X344488Y266536I0J1968D01*
G01X342520Y634252D02*
G03X344488Y636221I0J1968D01*
G01X346457Y270473D02*
G03X344488Y268504I0J-1969D01*
G01X346457Y270473D02*
X535433D01*
G01X344488Y268504D02*
Y266536D01*
G01X350394Y320473D02*
G03X348426Y318504I0J-1968D01*
G01Y316536D02*
G03X350394Y314567I1968J-1D01*
G01D02*
X456693D01*
G01Y320473D02*
X350394D01*
G01X348426Y318504D02*
Y316536D01*
G01X346457Y640158D02*
G03X344488Y638189I0J-1969D01*
G01X346457Y640158D02*
X535433D01*
G01X344488Y638189D02*
Y636221D01*
G01X350394Y690158D02*
G03X348426Y688189I0J-1968D01*
G01Y686221D02*
G03X350394Y684252I1968J-1D01*
G01D02*
X456693D01*
G01Y690158D02*
X350394D01*
G01X348426Y688189D02*
Y686221D01*
G01X383859Y1969D02*
G03X385827Y0I1968J-1D01*
G01D02*
X523622D01*
G01X372048D02*
G03X375985Y3937I0J3937D01*
G01X383859Y1969D02*
Y32677D01*
G01X375985Y3937D02*
Y94488D01*
G01X383859Y32677D02*
G03X375985I-3937J0D01*
G01Y57874D02*
G03X383859I3937J0D01*
G01D02*
Y90551D01*
G01X379922Y98425D02*
G03X375985Y94488I0J-3937D01*
G01X458071Y90551D02*
X383859D01*
G01X462008Y98425D02*
X379922D01*
G01X375985Y166334D02*
G03X377953Y164365I1969J0D01*
G01X375985Y180113D02*
Y166334D01*
G01X377953Y164365D02*
X484252D01*
G01X377953Y182082D02*
G03X375985Y180113I0J-1968D01*
G01X484252Y182082D02*
X377953D01*
G01X383859Y369685D02*
X465355D01*
G01X372048D02*
G03X375985Y373622I0J3937D01*
G01X383859Y369685D02*
Y402362D01*
G01X375985Y373622D02*
Y464173D01*
G01X383859Y402362D02*
G03X375985I-3937J0D01*
G01Y427559D02*
G03X383859I3937J0D01*
G01D02*
Y460236D01*
G01X379922Y468110D02*
G03X375985Y464173I0J-3937D01*
G01X458071Y460236D02*
X383859D01*
G01X462008Y468110D02*
X379922D01*
G01X375985Y536019D02*
G03X377953Y534050I1969J0D01*
G01D02*
X484252D01*
G01X377953Y551767D02*
G03X375985Y549799I0J-1968D01*
G01D02*
Y536019D01*
G01X484252Y551767D02*
X377953D01*
G01X429922Y260630D02*
Y266536D01*
G01X425985Y256693D02*
G03X429922Y260630I0J3937D01*
G01Y266536D02*
G03X425985Y270473I-3937J0D01*
G01X429922Y630315D02*
Y636221D01*
G01X425985Y626378D02*
G03X429922Y630315I0J3937D01*
G01Y636221D02*
G03X425985Y640158I-3937J0D01*
G01X452756Y260630D02*
G03X456693Y256693I3937J0D01*
G01X452756Y260630D02*
Y266536D01*
G01X456693Y270473D02*
G03X452756Y266536I0J-3937D01*
G01X458662Y318504D02*
G03X456693Y320473I-1969J0D01*
G01Y314567D02*
G03X458662Y316536I0J1969D01*
G01X452756Y630315D02*
G03X456693Y626378I3937J0D01*
G01X452756Y630315D02*
Y636221D01*
G01X456693Y640158D02*
G03X452756Y636221I0J-3937D01*
G01X458662Y688189D02*
G03X456693Y690158I-1969J0D01*
G01Y684252D02*
G03X458662Y686221I0J1969D01*
G01X458071Y78937D02*
G03X469882Y67126I11811J0D01*
G01X465945Y78937D02*
G03X469882Y75000I3937J0D01*
G01X458071Y90551D02*
Y78937D01*
G01X465945Y94488D02*
Y78937D01*
G01X469882Y67126D02*
X525591D01*
G01X469882Y75000D02*
X529528D01*
G01X465945Y94488D02*
G03X462008Y98425I-3937J0D01*
G01X458662Y316536D02*
Y318504D01*
G01X465355Y361811D02*
G03Y369685I0J3937D01*
G01X458071Y448622D02*
G03X469882Y436811I11811J0D01*
G01D02*
X525591D01*
G01X465945Y448622D02*
G03X469882Y444685I3937J0D01*
G01X465945Y464173D02*
G03X462008Y468110I-3937J0D01*
G01X458071Y460236D02*
Y448622D01*
G01X465945Y464173D02*
Y448622D01*
G01X469882Y444685D02*
X529528D01*
G01X458662Y686221D02*
Y688189D01*
G01X484252Y164365D02*
G03X486221Y166334I0J1969D01*
G01D02*
Y180113D01*
G01D02*
G03X484252Y182082I-1969J0D01*
G01X496063Y369685D02*
G03Y361811I0J-3937D01*
G01Y369685D02*
X525591D01*
G01X484252Y534050D02*
G03X486221Y536019I0J1969D01*
G01Y549799D02*
G03X484252Y551767I-1969J-1D01*
G01X486221Y536019D02*
Y549799D01*
G01X523622Y0D02*
G03X525591Y1969I0J1969D01*
G01X533465Y3937D02*
G03X537402Y0I3937J0D01*
G01X525591Y1969D02*
Y20965D01*
G01X533465Y3937D02*
Y71063D01*
G01X537402Y0D02*
X561024D01*
G01X533465Y20965D02*
G03X525591I-3937J0D01*
G01Y46162D02*
G03X533465I3937J0D01*
G01X525591D02*
Y67126D01*
G01X533465Y71063D02*
G03X529528Y75000I-3937J0D01*
G01X535433Y270473D02*
G03X539370Y274410I0J3937D01*
G01D02*
Y357874D01*
G01X547244Y270473D02*
X562992D01*
G01X547244D02*
Y303543D01*
G01D02*
G03X539370I-3937J0D01*
G01Y328740D02*
G03X547244I3937J0D01*
G01D02*
Y361811D01*
G01X539370Y357874D02*
G03X535433Y361811I-3937J0D01*
G01X547244D02*
X562992D01*
G01X533465Y373622D02*
G03X537402Y369685I3937J0D01*
G01X525591D02*
Y390650D01*
G01X533465Y373622D02*
Y440748D01*
G01X537402Y369685D02*
X561024D01*
G01X533465Y390650D02*
G03X525591I-3937J0D01*
G01Y415847D02*
G03X533465I3937J0D01*
G01X525591D02*
Y436811D01*
G01X533465Y440748D02*
G03X529528Y444685I-3937J0D01*
G01X535433Y640158D02*
G03X539370Y644095I0J3937D01*
G01D02*
Y727559D01*
G01X547244Y640158D02*
X562992D01*
G01X547244D02*
Y673228D01*
G01D02*
G03X539370I-3937J0D01*
G01Y698425D02*
G03X547244I3937J0D01*
G01D02*
Y727559D01*
G01X551181Y731496D02*
G03X547244Y727559I0J-3937D01*
G01X539370D02*
G03X535433Y731496I-3937J0D01*
G01X561024Y0D02*
G03X564961Y3937I0J3937D01*
G01D02*
Y252756D01*
G01D02*
G03X561024Y256693I-3937J0D01*
G01X562992Y270473D02*
G03X564961Y272441I1J1968D01*
G01D02*
Y359843D01*
G01D02*
G03X562992Y361811I-1968J0D01*
G01X561024Y369685D02*
G03X564961Y373622I0J3937D01*
G01D02*
Y622441D01*
G01D02*
G03X561024Y626378I-3937J0D01*
G01X562992Y640158D02*
G03X564961Y642126I1J1968D01*
G01D02*
Y721654D01*
G01D02*
G03X555118Y731496I-9842J0D01*
G01X551181D02*
X555118D01*
G54D12*
G01X321631Y75454D02*
X320434Y81328D01*
G01X320069Y74400D02*
X318584Y81688D01*
G01X324460Y73581D02*
X321631Y75454D01*
G01X324100Y71732D02*
X320069Y74400D01*
G01D02*
X318584Y81688D01*
G01X321631Y75454D02*
X320434Y81328D01*
G01X324100Y71732D02*
X320069Y74400D01*
G01X324460Y73581D02*
X321631Y75454D01*
G01X321331Y85834D02*
X324766Y86533D01*
G01X320434Y81328D02*
X322384Y84272D01*
G01X318584Y81688D02*
X321331Y85834D01*
G01D02*
X324766Y86533D01*
G01X318584Y81688D02*
X321331Y85834D01*
G01X320434Y81328D02*
X322384Y84272D01*
G01X326929Y74083D02*
X324460Y73581D01*
G01X341193Y75209D02*
X324100Y71732D01*
G01X333632Y75447D02*
X331163Y74945D01*
G01X341193Y75209D02*
X324100Y71732D01*
G01X340515Y76847D02*
X337866Y76308D01*
G01X341193Y75209D02*
X324100Y71732D01*
G01X344872Y79731D02*
X340515Y76847D01*
G01X357536Y86026D02*
X341193Y75209D01*
G01X357536Y86026D02*
X341193Y75209D01*
G01X357536Y86026D02*
X341193Y75209D01*
G01D02*
X324100Y71732D01*
G01X326929Y74083D02*
X324460Y73581D01*
G01X333632Y75447D02*
X331163Y74945D01*
G01X340515Y76847D02*
X337866Y76308D01*
G01X357536Y86026D02*
X341193Y75209D01*
G01X344872Y79731D02*
X340515Y76847D01*
G01X339902Y84577D02*
X341898D01*
G01X340426Y86317D02*
X341898D01*
G01X333556Y88777D02*
X339902Y84577D01*
G01X340426Y86317D02*
X341898D01*
G01X335118Y89830D02*
X340426Y86317D01*
G01X332484Y94053D02*
X333556Y88777D01*
G01X334260Y94053D02*
X335118Y89830D01*
G01X333512Y99103D02*
X332484Y94053D01*
G01X335150Y98425D02*
X334260Y94053D01*
G01X339404Y108004D02*
X333512Y99103D01*
G01X341042Y107326D02*
X335150Y98425D01*
G01X340426Y86317D02*
X341898D01*
G01X339902Y84577D02*
X341898D01*
G01X333556Y88777D02*
X339902Y84577D01*
G01X335118Y89830D02*
X340426Y86317D01*
G01X333556Y88777D02*
X339902Y84577D01*
G01X334260Y94053D02*
X335118Y89830D01*
G01X332484Y94053D02*
X333556Y88777D01*
G01X335150Y98425D02*
X334260Y94053D01*
G01X333512Y99103D02*
X332484Y94053D01*
G01X341042Y107326D02*
X335150Y98425D01*
G01X339404Y108004D02*
X333512Y99103D01*
G01X324942Y84793D02*
X326274D01*
G01X324766Y86533D02*
X326313D01*
G01X322384Y84272D02*
X324942Y84793D01*
G01X324766Y86533D02*
X326313D01*
G01X324942Y84793D02*
X326274D01*
G01X322384Y84272D02*
X324942Y84793D01*
G01X350546Y162770D02*
X339404Y108004D01*
G01X341544Y109795D02*
X341042Y107326D01*
G01X342908Y116498D02*
X342406Y114029D01*
G01X344272Y123201D02*
X343770Y120732D01*
G01X341544Y109795D02*
X341042Y107326D01*
G01X350546Y162770D02*
X339404Y108004D01*
G01X342908Y116498D02*
X342406Y114029D01*
G01X350546Y162770D02*
X339404Y108004D01*
G01X344272Y123201D02*
X343770Y120732D01*
G01X350546Y162770D02*
X339404Y108004D01*
G01X350546Y162770D02*
X339404Y108004D01*
G01X350546Y162770D02*
X339404Y108004D01*
G01X350576Y83507D02*
X348475Y82116D01*
G01X356280Y87282D02*
X354179Y85891D01*
G01X357671Y89383D02*
X356280Y87282D01*
G01X387790Y131734D02*
X357536Y86026D01*
G01X361446Y95087D02*
X360055Y92986D01*
G01X387790Y131734D02*
X357536Y86026D01*
G01X365221Y100791D02*
X363830Y98690D01*
G01X387790Y131734D02*
X357536Y86026D01*
G01X387790Y131734D02*
X357536Y86026D01*
G01X387790Y131734D02*
X357536Y86026D01*
G01X387790Y131734D02*
X357536Y86026D01*
G01X387790Y131734D02*
X357536Y86026D01*
G01X350576Y83507D02*
X348475Y82116D01*
G01X356280Y87282D02*
X354179Y85891D01*
G01X387790Y131734D02*
X357536Y86026D01*
G01X357671Y89383D02*
X356280Y87282D01*
G01X361446Y95087D02*
X360055Y92986D01*
G01X365221Y100791D02*
X363830Y98690D01*
G01X345636Y129904D02*
X345134Y127435D01*
G01X352184Y162092D02*
X346497Y134138D01*
G01X345636Y129904D02*
X345134Y127435D01*
G01X352184Y162092D02*
X346497Y134138D01*
G01X364145Y183317D02*
X350546Y162770D01*
G01X365401Y182061D02*
X352184Y162092D01*
G01X365401Y182061D02*
X352184Y162092D01*
G01X364145Y183317D02*
X350546Y162770D01*
G01X384241Y196618D02*
X364145Y183317D01*
G01X385497Y195362D02*
X365401Y182061D01*
G01X385497Y195362D02*
X365401Y182061D01*
G01X384241Y196618D02*
X364145Y183317D01*
G01X368996Y106495D02*
X367605Y104394D01*
G01X377781Y119766D02*
X371381Y110098D01*
G01X381557Y125470D02*
X380166Y123369D01*
G01X368996Y106495D02*
X367605Y104394D01*
G01X377781Y119766D02*
X371381Y110098D01*
G01X381557Y125470D02*
X380166Y123369D01*
G01X386152Y132412D02*
X383942Y129073D01*
G01X386517Y134208D02*
X386152Y132412D01*
G01X388257Y134032D02*
X387790Y131734D01*
G01X386517Y135806D02*
Y134208D01*
G01X388257Y136918D02*
Y134032D01*
G01X386152Y132412D02*
X383942Y129073D01*
G01X388257Y134032D02*
X387790Y131734D01*
G01X386517Y134208D02*
X386152Y132412D01*
G01X388257Y136918D02*
Y134032D01*
G01X386517Y135806D02*
Y134208D01*
G01X386167Y199529D02*
X384241Y196618D01*
G01X387907Y199005D02*
X385497Y195362D01*
G01X386167Y201904D02*
Y199529D01*
G01X387907Y202316D02*
Y199005D01*
G01D02*
X385497Y195362D01*
G01X386167Y199529D02*
X384241Y196618D01*
G01X387907Y202316D02*
Y199005D01*
G01X386167Y201904D02*
Y199529D01*
M02*
